(kicad_pcb
	(version 20260206)
	(generator "pcbnew")
	(generator_version "10.0")
	(general
		(thickness 1.6)
		(legacy_teardrops no)
	)
	(paper "A4")
	(title_block
		(title "Bryce Canyon_SCC_16316-1_OCP.brd")
		(comment 1 "Bryce Canyon / footprints 1488-1496 of 1561")
	)
	(layers
		(0 "F.Cu" signal "TOP")
		(4 "In1.Cu" signal "L2GND")
		(6 "In2.Cu" signal "L3")
		(8 "In3.Cu" signal "L4VCC")
		(10 "In4.Cu" signal "L5VCC")
		(12 "In5.Cu" signal "L6")
		(14 "In6.Cu" signal "L7GND")
		(2 "B.Cu" signal "BOTTOM")
		(9 "F.Adhes" user "F.Adhesive")
		(11 "B.Adhes" user "B.Adhesive")
		(13 "F.Paste" user "Package Geometry/Pastemask Top")
		(15 "B.Paste" user "Package Geometry/Pastemask Bottom")
		(5 "F.SilkS" user "Ref Des/Silkscreen Top")
		(7 "B.SilkS" user "Ref Des/Silkscreen Bottom")
		(1 "F.Mask" user "Board Geometry/Soldermask Top")
		(3 "B.Mask" user "Board Geometry/Soldermask Bottom")
		(17 "Dwgs.User" user "User.Drawings")
		(19 "Cmts.User" user "User.Comments")
		(21 "Eco1.User" user "User.Eco1")
		(23 "Eco2.User" user "User.Eco2")
		(25 "Edge.Cuts" user "Board Geometry/Outline")
		(27 "Margin" user)
		(31 "F.CrtYd" user "Package Geometry/Place Bound Top")
		(29 "B.CrtYd" user "Package Geometry/Place Bound Bottom")
		(35 "F.Fab" user "Ref Des/Assembly Top")
		(33 "B.Fab" user "Ref Des/Assembly Bottom")
	)
	(footprint ""
		(layer "B.Cu")
		(at 120.523 -68.7324 -90)
		(property "Reference" "C215"
			(at 0 0 90)
			(layer "B.SilkS")
			(hide yes)
			(effects
				(font
					(size 1.27 1.27)
				)
				(justify mirror)
			)
		)
		(property "Value" "SCD1U16V2KX-3GP"
			(at -1.1811 -2.7051 270)
			(unlocked yes)
			(layer "B.Fab")
			(hide yes)
			(effects
				(font
					(size 1.016 1.016)
					(thickness 0.1524)
				)
				(justify mirror)
			)
		)
		(property "Device Type" "C402H22"
			(at -1.1811 -4.2291 270)
			(unlocked yes)
			(layer "B.Fab")
			(hide yes)
			(effects
				(font
					(size 1.016 1.016)
					(thickness 0.1524)
				)
				(justify mirror)
			)
		)
		(duplicate_pad_numbers_are_jumpers no)
		(fp_rect
			(start 0.4318 0.9525)
			(end -0.4318 -0.9525)
			(stroke
				(width 0)
				(type default)
			)
			(fill no)
			(layer "B.CrtYd")
		)
		(fp_rect
			(start 0.4318 0.9525)
			(end -0.4318 -0.9525)
			(stroke
				(width 0)
				(type default)
			)
			(fill no)
			(layer "B.Fab")
		)
		(pad "1" smd custom
			(at 0 -0.4445 90)
			(size 0.1524 0.1524)
			(layers "B.Cu" "B.Mask" "B.Paste")
			(net "GB_VDDH")
			(options
				(clearance outline)
				(anchor circle)
			)
			(primitives
				(gr_poly
					(pts
						(arc
							(start 0.3048 0.2032)
							(mid 0.275042 0.275042)
							(end 0.2032 0.3048)
						)
						(arc
							(start -0.2032 0.3048)
							(mid -0.275042 0.275042)
							(end -0.3048 0.2032)
						)
						(arc
							(start -0.3048 -0.2032)
							(mid -0.275042 -0.275042)
							(end -0.2032 -0.3048)
						)
						(arc
							(start 0.2032 -0.3048)
							(mid 0.275042 -0.275042)
							(end 0.3048 -0.2032)
						)
					)
					(width 0)
					(fill yes)
				)
			)
		)
		(pad "2" smd custom
			(at 0 0.4445 90)
			(size 0.1524 0.1524)
			(layers "B.Cu" "B.Mask" "B.Paste")
			(net "GND")
			(options
				(clearance outline)
				(anchor circle)
			)
			(primitives
				(gr_poly
					(pts
						(arc
							(start 0.3048 0.2032)
							(mid 0.275042 0.275042)
							(end 0.2032 0.3048)
						)
						(arc
							(start -0.2032 0.3048)
							(mid -0.275042 0.275042)
							(end -0.3048 0.2032)
						)
						(arc
							(start -0.3048 -0.2032)
							(mid -0.275042 -0.275042)
							(end -0.2032 -0.3048)
						)
						(arc
							(start 0.2032 -0.3048)
							(mid 0.275042 -0.275042)
							(end 0.3048 -0.2032)
						)
					)
					(width 0)
					(fill yes)
				)
			)
		)
	)
	(footprint ""
		(layer "B.Cu")
		(at 165.283388 -46.593506)
		(property "Reference" "TP85"
			(at 0 0 0)
			(layer "B.SilkS")
			(hide yes)
			(effects
				(font
					(size 1.27 1.27)
				)
				(justify mirror)
			)
		)
		(property "Value" "TPAD28-2-GP"
			(at 0.0127 -1.6637 0)
			(unlocked yes)
			(layer "B.Fab")
			(hide yes)
			(effects
				(font
					(size 1.016 1.016)
					(thickness 0.1524)
				)
				(justify mirror)
			)
		)
		(property "Device Type" "TPAD28"
			(at 0.0127 -3.1877 0)
			(unlocked yes)
			(layer "B.Fab")
			(hide yes)
			(effects
				(font
					(size 1.016 1.016)
					(thickness 0.1524)
				)
				(justify mirror)
			)
		)
		(duplicate_pad_numbers_are_jumpers no)
		(fp_poly
			(pts
				(arc
					(start 0.3556 0)
					(mid -0.3556 0)
					(end 0.3556 0)
				)
			)
			(stroke
				(width 0)
				(type default)
			)
			(fill no)
			(layer "B.CrtYd")
		)
		(fp_poly
			(pts
				(arc
					(start 0.6096 0)
					(mid -0.6096 0)
					(end 0.6096 0)
				)
			)
			(stroke
				(width 0)
				(type default)
			)
			(fill no)
			(layer "B.Fab")
		)
		(pad "1" smd circle
			(at 0 0 180)
			(size 0.7112 0.7112)
			(layers "B.Cu" "B.Mask" "B.Paste")
			(net "SIO_LOAD_0")
		)
	)
	(footprint ""
		(layer "B.Cu")
		(at 183.144668 -48.05299 -90)
		(property "Reference" "C481"
			(at 0 0 90)
			(layer "B.SilkS")
			(hide yes)
			(effects
				(font
					(size 1.27 1.27)
				)
				(justify mirror)
			)
		)
		(property "Value" "SCD1U6D3V1KX-GP"
			(at 2.8321 -1.7399 270)
			(unlocked yes)
			(layer "B.Fab")
			(hide yes)
			(effects
				(font
					(size 1.016 1.016)
					(thickness 0.1524)
				)
				(justify mirror)
			)
		)
		(property "Device Type" "C0201H13"
			(at 2.8321 -3.2639 270)
			(unlocked yes)
			(layer "B.Fab")
			(hide yes)
			(effects
				(font
					(size 1.016 1.016)
					(thickness 0.1524)
				)
				(justify mirror)
			)
		)
		(duplicate_pad_numbers_are_jumpers no)
		(fp_rect
			(start 0.2794 0.6477)
			(end -0.2794 -0.6477)
			(stroke
				(width 0)
				(type default)
			)
			(fill no)
			(layer "B.CrtYd")
		)
		(fp_rect
			(start 0.2794 0.6477)
			(end -0.2794 -0.6477)
			(stroke
				(width 0)
				(type default)
			)
			(fill no)
			(layer "B.Fab")
		)
		(pad "1" smd custom
			(at 0 -0.2794 90)
			(size 0.0762 0.0762)
			(layers "B.Cu" "B.Mask" "B.Paste")
			(net "P1V8_C")
			(options
				(clearance outline)
				(anchor circle)
			)
			(primitives
				(gr_poly
					(pts
						(arc
							(start 0.1524 0.127)
							(mid 0.137521 0.162921)
							(end 0.1016 0.1778)
						)
						(arc
							(start -0.1016 0.1778)
							(mid -0.137521 0.162921)
							(end -0.1524 0.127)
						)
						(arc
							(start -0.1524 -0.127)
							(mid -0.137521 -0.162921)
							(end -0.1016 -0.1778)
						)
						(arc
							(start 0.1016 -0.1778)
							(mid 0.137521 -0.162921)
							(end 0.1524 -0.127)
						)
					)
					(width 0)
					(fill yes)
				)
			)
		)
		(pad "2" smd custom
			(at 0 0.2794 90)
			(size 0.0762 0.0762)
			(layers "B.Cu" "B.Mask" "B.Paste")
			(net "GND")
			(options
				(clearance outline)
				(anchor circle)
			)
			(primitives
				(gr_poly
					(pts
						(arc
							(start 0.1524 0.127)
							(mid 0.137521 0.162921)
							(end 0.1016 0.1778)
						)
						(arc
							(start -0.1016 0.1778)
							(mid -0.137521 0.162921)
							(end -0.1524 0.127)
						)
						(arc
							(start -0.1524 -0.127)
							(mid -0.137521 -0.162921)
							(end -0.1016 -0.1778)
						)
						(arc
							(start 0.1016 -0.1778)
							(mid 0.137521 -0.162921)
							(end 0.1524 -0.127)
						)
					)
					(width 0)
					(fill yes)
				)
			)
		)
	)
	(footprint ""
		(layer "B.Cu")
		(at 168.98239 -21.006816)
		(property "Reference" "C315"
			(at 0 0 0)
			(layer "B.SilkS")
			(hide yes)
			(effects
				(font
					(size 1.27 1.27)
				)
				(justify mirror)
			)
		)
		(property "Value" "SCD22U10V1KX-GP"
			(at 2.8321 -1.7399 0)
			(unlocked yes)
			(layer "B.Fab")
			(hide yes)
			(effects
				(font
					(size 1.016 1.016)
					(thickness 0.1524)
				)
				(justify mirror)
			)
		)
		(property "Device Type" "C0201H13"
			(at 2.8321 -3.2639 0)
			(unlocked yes)
			(layer "B.Fab")
			(hide yes)
			(effects
				(font
					(size 1.016 1.016)
					(thickness 0.1524)
				)
				(justify mirror)
			)
		)
		(duplicate_pad_numbers_are_jumpers no)
		(fp_rect
			(start 0.2794 0.6477)
			(end -0.2794 -0.6477)
			(stroke
				(width 0)
				(type default)
			)
			(fill no)
			(layer "B.CrtYd")
		)
		(fp_rect
			(start 0.2794 0.6477)
			(end -0.2794 -0.6477)
			(stroke
				(width 0)
				(type default)
			)
			(fill no)
			(layer "B.Fab")
		)
		(pad "1" smd custom
			(at 0 -0.2794 180)
			(size 0.0762 0.0762)
			(layers "B.Cu" "B.Mask" "B.Paste")
			(net "PCIE_SCC_TO_COMP_C_2_DP")
			(options
				(clearance outline)
				(anchor circle)
			)
			(primitives
				(gr_poly
					(pts
						(arc
							(start 0.1524 0.127)
							(mid 0.137521 0.162921)
							(end 0.1016 0.1778)
						)
						(arc
							(start -0.1016 0.1778)
							(mid -0.137521 0.162921)
							(end -0.1524 0.127)
						)
						(arc
							(start -0.1524 -0.127)
							(mid -0.137521 -0.162921)
							(end -0.1016 -0.1778)
						)
						(arc
							(start 0.1016 -0.1778)
							(mid 0.137521 -0.162921)
							(end 0.1524 -0.127)
						)
					)
					(width 0)
					(fill yes)
				)
			)
		)
		(pad "2" smd custom
			(at 0 0.2794 180)
			(size 0.0762 0.0762)
			(layers "B.Cu" "B.Mask" "B.Paste")
			(net "PCIE_SCC_TO_COMP_2_DP")
			(options
				(clearance outline)
				(anchor circle)
			)
			(primitives
				(gr_poly
					(pts
						(arc
							(start 0.1524 0.127)
							(mid 0.137521 0.162921)
							(end 0.1016 0.1778)
						)
						(arc
							(start -0.1016 0.1778)
							(mid -0.137521 0.162921)
							(end -0.1524 0.127)
						)
						(arc
							(start -0.1524 -0.127)
							(mid -0.137521 -0.162921)
							(end -0.1016 -0.1778)
						)
						(arc
							(start 0.1016 -0.1778)
							(mid 0.137521 -0.162921)
							(end 0.1524 -0.127)
						)
					)
					(width 0)
					(fill yes)
				)
			)
		)
	)
	(footprint ""
		(layer "B.Cu")
		(at 106.0196 -86.9442)
		(property "Reference" "R86"
			(at 0 0 0)
			(layer "B.SilkS")
			(hide yes)
			(effects
				(font
					(size 1.27 1.27)
				)
				(justify mirror)
			)
		)
		(property "Value" "4K75R2F-1-GP"
			(at -0.064008 -3.993896 0)
			(unlocked yes)
			(layer "B.Fab")
			(hide yes)
			(effects
				(font
					(size 1.016 1.016)
					(thickness 0.1524)
				)
				(justify mirror)
			)
		)
		(property "Device Type" "R402H16"
			(at -0.064008 -5.517896 0)
			(unlocked yes)
			(layer "B.Fab")
			(hide yes)
			(effects
				(font
					(size 1.016 1.016)
					(thickness 0.1524)
				)
				(justify mirror)
			)
		)
		(duplicate_pad_numbers_are_jumpers no)
		(fp_line
			(start -0.508 -0.9398)
			(end 0.508 -0.9398)
			(stroke
				(width 0.1524)
				(type default)
			)
			(layer "B.SilkS")
		)
		(fp_line
			(start 0.508 -0.9398)
			(end 0.508 0.9398)
			(stroke
				(width 0.1524)
				(type default)
			)
			(layer "B.SilkS")
		)
		(fp_rect
			(start 0.508 0.9398)
			(end -0.508 -0.9398)
			(stroke
				(width 0)
				(type default)
			)
			(fill no)
			(layer "B.CrtYd")
		)
		(fp_rect
			(start 0.508 0.9398)
			(end -0.508 -0.9398)
			(stroke
				(width 0)
				(type default)
			)
			(fill no)
			(layer "B.Fab")
		)
		(pad "1" smd custom
			(at 0 -0.4445 180)
			(size 0.1397 0.1397)
			(layers "B.Cu" "B.Mask" "B.Paste")
			(net "P1V8_E")
			(options
				(clearance outline)
				(anchor circle)
			)
			(primitives
				(gr_poly
					(pts
						(arc
							(start -0.1778 0.2794)
							(mid -0.249642 0.249642)
							(end -0.2794 0.1778)
						)
						(arc
							(start -0.2794 -0.1778)
							(mid -0.249642 -0.249642)
							(end -0.1778 -0.2794)
						)
						(arc
							(start 0.1778 -0.2794)
							(mid 0.249642 -0.249642)
							(end 0.2794 -0.1778)
						)
						(arc
							(start 0.2794 0.1778)
							(mid 0.249642 0.249642)
							(end 0.1778 0.2794)
						)
					)
					(width 0)
					(fill yes)
				)
			)
		)
		(pad "2" smd custom
			(at 0 0.4445 180)
			(size 0.1397 0.1397)
			(layers "B.Cu" "B.Mask" "B.Paste")
			(net "SXP_ACTIVE_1")
			(options
				(clearance outline)
				(anchor circle)
			)
			(primitives
				(gr_poly
					(pts
						(arc
							(start -0.1778 0.2794)
							(mid -0.249642 0.249642)
							(end -0.2794 0.1778)
						)
						(arc
							(start -0.2794 -0.1778)
							(mid -0.249642 -0.249642)
							(end -0.1778 -0.2794)
						)
						(arc
							(start 0.1778 -0.2794)
							(mid 0.249642 -0.249642)
							(end 0.2794 -0.1778)
						)
						(arc
							(start 0.2794 0.1778)
							(mid 0.249642 0.249642)
							(end 0.1778 0.2794)
						)
					)
					(width 0)
					(fill yes)
				)
			)
		)
	)
	(footprint ""
		(layer "B.Cu")
		(at 113.2586 -66.3575)
		(property "Reference" "C180"
			(at 0 0 0)
			(layer "B.SilkS")
			(hide yes)
			(effects
				(font
					(size 1.27 1.27)
				)
				(justify mirror)
			)
		)
		(property "Value" "SCD1U6D3V1KX-GP"
			(at 2.8321 -1.7399 0)
			(unlocked yes)
			(layer "B.Fab")
			(hide yes)
			(effects
				(font
					(size 1.016 1.016)
					(thickness 0.1524)
				)
				(justify mirror)
			)
		)
		(property "Device Type" "C0201H13"
			(at 2.8321 -3.2639 0)
			(unlocked yes)
			(layer "B.Fab")
			(hide yes)
			(effects
				(font
					(size 1.016 1.016)
					(thickness 0.1524)
				)
				(justify mirror)
			)
		)
		(duplicate_pad_numbers_are_jumpers no)
		(fp_rect
			(start 0.2794 0.6477)
			(end -0.2794 -0.6477)
			(stroke
				(width 0)
				(type default)
			)
			(fill no)
			(layer "B.CrtYd")
		)
		(fp_rect
			(start 0.2794 0.6477)
			(end -0.2794 -0.6477)
			(stroke
				(width 0)
				(type default)
			)
			(fill no)
			(layer "B.Fab")
		)
		(pad "1" smd custom
			(at 0 -0.2794 180)
			(size 0.0762 0.0762)
			(layers "B.Cu" "B.Mask" "B.Paste")
			(net "P0V9")
			(options
				(clearance outline)
				(anchor circle)
			)
			(primitives
				(gr_poly
					(pts
						(arc
							(start 0.1524 0.127)
							(mid 0.137521 0.162921)
							(end 0.1016 0.1778)
						)
						(arc
							(start -0.1016 0.1778)
							(mid -0.137521 0.162921)
							(end -0.1524 0.127)
						)
						(arc
							(start -0.1524 -0.127)
							(mid -0.137521 -0.162921)
							(end -0.1016 -0.1778)
						)
						(arc
							(start 0.1016 -0.1778)
							(mid 0.137521 -0.162921)
							(end 0.1524 -0.127)
						)
					)
					(width 0)
					(fill yes)
				)
			)
		)
		(pad "2" smd custom
			(at 0 0.2794 180)
			(size 0.0762 0.0762)
			(layers "B.Cu" "B.Mask" "B.Paste")
			(net "GND")
			(options
				(clearance outline)
				(anchor circle)
			)
			(primitives
				(gr_poly
					(pts
						(arc
							(start 0.1524 0.127)
							(mid 0.137521 0.162921)
							(end 0.1016 0.1778)
						)
						(arc
							(start -0.1016 0.1778)
							(mid -0.137521 0.162921)
							(end -0.1524 0.127)
						)
						(arc
							(start -0.1524 -0.127)
							(mid -0.137521 -0.162921)
							(end -0.1016 -0.1778)
						)
						(arc
							(start 0.1016 -0.1778)
							(mid 0.137521 -0.162921)
							(end 0.1524 -0.127)
						)
					)
					(width 0)
					(fill yes)
				)
			)
		)
	)
	(footprint ""
		(layer "B.Cu")
		(at 107.499912 -77.499972)
		(property "Reference" "TP26"
			(at 0 0 0)
			(layer "B.SilkS")
			(hide yes)
			(effects
				(font
					(size 1.27 1.27)
				)
				(justify mirror)
			)
		)
		(property "Value" "TPAD28-2-GP"
			(at 0.0127 -1.6637 0)
			(unlocked yes)
			(layer "B.Fab")
			(hide yes)
			(effects
				(font
					(size 1.016 1.016)
					(thickness 0.1524)
				)
				(justify mirror)
			)
		)
		(property "Device Type" "TPAD28"
			(at 0.0127 -3.1877 0)
			(unlocked yes)
			(layer "B.Fab")
			(hide yes)
			(effects
				(font
					(size 1.016 1.016)
					(thickness 0.1524)
				)
				(justify mirror)
			)
		)
		(duplicate_pad_numbers_are_jumpers no)
		(fp_poly
			(pts
				(arc
					(start 0.3556 0)
					(mid -0.3556 0)
					(end 0.3556 0)
				)
			)
			(stroke
				(width 0)
				(type default)
			)
			(fill no)
			(layer "B.CrtYd")
		)
		(fp_poly
			(pts
				(arc
					(start 0.6096 0)
					(mid -0.6096 0)
					(end 0.6096 0)
				)
			)
			(stroke
				(width 0)
				(type default)
			)
			(fill no)
			(layer "B.Fab")
		)
		(pad "1" smd circle
			(at 0 0 180)
			(size 0.7112 0.7112)
			(layers "B.Cu" "B.Mask" "B.Paste")
			(net "SXP_ACTIVE_0")
		)
	)
	(footprint ""
		(layer "B.Cu")
		(at 164.3126 -92.6846 90)
		(property "Reference" "C645"
			(at 0 0 90)
			(layer "B.SilkS")
			(hide yes)
			(effects
				(font
					(size 1.27 1.27)
				)
				(justify mirror)
			)
		)
		(property "Value" "SC10U16V5KX-7-GP-U"
			(at 0.0762 -6.1214 90)
			(unlocked yes)
			(layer "B.Fab")
			(hide yes)
			(effects
				(font
					(size 1.016 1.016)
					(thickness 0.1524)
				)
				(justify mirror)
			)
		)
		(property "Device Type" "C805H58"
			(at 0.0762 -8.1534 90)
			(unlocked yes)
			(layer "B.Fab")
			(hide yes)
			(effects
				(font
					(size 1.016 1.016)
					(thickness 0.1524)
				)
				(justify mirror)
			)
		)
		(duplicate_pad_numbers_are_jumpers no)
		(fp_line
			(start -0.635 0)
			(end 0.635 0)
			(stroke
				(width 0.508)
				(type default)
			)
			(layer "B.SilkS")
		)
		(fp_rect
			(start 0.9652 1.778)
			(end -0.9652 -1.778)
			(stroke
				(width 0)
				(type default)
			)
			(fill no)
			(layer "B.CrtYd")
		)
		(fp_poly
			(pts
				(xy 0.9652 -1.778) (xy -0.9652 -1.778) (xy -0.9652 1.778) (xy 0.9652 1.778)
			)
			(stroke
				(width 0)
				(type default)
			)
			(fill no)
			(layer "B.Fab")
		)
		(pad "1" smd rect
			(at 0 -0.9652 270)
			(size 1.397 1.143)
			(layers "B.Cu" "B.Mask" "B.Paste")
			(net "P12V_SYBY_VDD_U6")
		)
		(pad "2" smd rect
			(at 0 0.9652 270)
			(size 1.397 1.143)
			(layers "B.Cu" "B.Mask" "B.Paste")
			(net "GND")
		)
	)
	(footprint ""
		(layer "B.Cu")
		(at 108.6358 -57.4802)
		(property "Reference" "C261"
			(at 0 0 0)
			(layer "B.SilkS")
			(hide yes)
			(effects
				(font
					(size 1.27 1.27)
				)
				(justify mirror)
			)
		)
		(property "Value" "SCD1U6D3V1KX-GP"
			(at 2.8321 -1.7399 0)
			(unlocked yes)
			(layer "B.Fab")
			(hide yes)
			(effects
				(font
					(size 1.016 1.016)
					(thickness 0.1524)
				)
				(justify mirror)
			)
		)
		(property "Device Type" "C0201H13"
			(at 2.8321 -3.2639 0)
			(unlocked yes)
			(layer "B.Fab")
			(hide yes)
			(effects
				(font
					(size 1.016 1.016)
					(thickness 0.1524)
				)
				(justify mirror)
			)
		)
		(duplicate_pad_numbers_are_jumpers no)
		(fp_rect
			(start 0.2794 0.6477)
			(end -0.2794 -0.6477)
			(stroke
				(width 0)
				(type default)
			)
			(fill no)
			(layer "B.CrtYd")
		)
		(fp_rect
			(start 0.2794 0.6477)
			(end -0.2794 -0.6477)
			(stroke
				(width 0)
				(type default)
			)
			(fill no)
			(layer "B.Fab")
		)
		(pad "1" smd custom
			(at 0 -0.2794 180)
			(size 0.0762 0.0762)
			(layers "B.Cu" "B.Mask" "B.Paste")
			(net "GB_VDDA")
			(options
				(clearance outline)
				(anchor circle)
			)
			(primitives
				(gr_poly
					(pts
						(arc
							(start 0.1524 0.127)
							(mid 0.137521 0.162921)
							(end 0.1016 0.1778)
						)
						(arc
							(start -0.1016 0.1778)
							(mid -0.137521 0.162921)
							(end -0.1524 0.127)
						)
						(arc
							(start -0.1524 -0.127)
							(mid -0.137521 -0.162921)
							(end -0.1016 -0.1778)
						)
						(arc
							(start 0.1016 -0.1778)
							(mid 0.137521 -0.162921)
							(end 0.1524 -0.127)
						)
					)
					(width 0)
					(fill yes)
				)
			)
		)
		(pad "2" smd custom
			(at 0 0.2794 180)
			(size 0.0762 0.0762)
			(layers "B.Cu" "B.Mask" "B.Paste")
			(net "GND")
			(options
				(clearance outline)
				(anchor circle)
			)
			(primitives
				(gr_poly
					(pts
						(arc
							(start 0.1524 0.127)
							(mid 0.137521 0.162921)
							(end 0.1016 0.1778)
						)
						(arc
							(start -0.1016 0.1778)
							(mid -0.137521 0.162921)
							(end -0.1524 0.127)
						)
						(arc
							(start -0.1524 -0.127)
							(mid -0.137521 -0.162921)
							(end -0.1016 -0.1778)
						)
						(arc
							(start 0.1016 -0.1778)
							(mid 0.137521 -0.162921)
							(end 0.1524 -0.127)
						)
					)
					(width 0)
					(fill yes)
				)
			)
		)
	)
)
